# BASEBOARD_FAB2 (Tioga Pass) — schematic netlist excerpt (pin names and nets, part order shuffled) for the footprints in the layout excerpt that follows; sources: Cadence DE-HDL packaged netlist, KiCad conversion of Wiwynn_Tioga_Pass_MB.brd

R4D20  RES  27.4 1% CHIP  pkg 0402  page 103 : A = CLK_100M_CPU0_BCLK1_R_DN ; B = CLK_100M_CPU0_BCLK1_DN
R9A20  RES  221 1.0% CHIP  pkg 0402  page 119 : A = FM_PWR_LED_A ; B = P3V3_STBY
R1D1  RES  33.2 1% CHIP  pkg 0402  page 206 : A = PWRGD_PVSA_CPU1_R ; B = PWRGD_PVSA_CPU1

(kicad_pcb
	(version 20260206)
	(generator "pcbnew")
	(generator_version "10.0")
	(general
		(thickness 1.6)
		(legacy_teardrops no)
	)
	(paper "A4")
	(title_block
		(title "Wiwynn_Tioga_Pass_MB.brd")
		(comment 1 "Tioga Pass / footprints 1387-1389 of 4770")
	)
	(layers
		(0 "F.Cu" signal "TOP")
		(4 "In1.Cu" signal "L2GND")
		(6 "In2.Cu" signal "L3")
		(8 "In3.Cu" signal "L4GND")
		(10 "In4.Cu" signal "L5")
		(12 "In5.Cu" signal "L6GND")
		(14 "In6.Cu" signal "L7VCC")
		(16 "In7.Cu" signal "L8VCC")
		(18 "In8.Cu" signal "L9GND")
		(20 "In9.Cu" signal "L10")
		(22 "In10.Cu" signal "L11GND")
		(24 "In11.Cu" signal "L12")
		(26 "In12.Cu" signal "L13GND")
		(2 "B.Cu" signal "BOTTOM")
		(9 "F.Adhes" user "F.Adhesive")
		(11 "B.Adhes" user "B.Adhesive")
		(13 "F.Paste" user "Package Geometry/Pastemask Top")
		(15 "B.Paste" user "Package Geometry/Pastemask Bottom")
		(5 "F.SilkS" user "Ref Des/Silkscreen Top")
		(7 "B.SilkS" user "Ref Des/Silkscreen Bottom")
		(1 "F.Mask" user "Board Geometry/Soldermask Top")
		(3 "B.Mask" user "Board Geometry/Soldermask Bottom")
		(17 "Dwgs.User" user "User.Drawings")
		(19 "Cmts.User" user "User.Comments")
		(21 "Eco1.User" user "User.Eco1")
		(23 "Eco2.User" user "User.Eco2")
		(25 "Edge.Cuts" user "Board Geometry/Outline")
		(27 "Margin" user)
		(31 "F.CrtYd" user "Package Geometry/Place Bound Top")
		(29 "B.CrtYd" user "Package Geometry/Place Bound Bottom")
		(35 "F.Fab" user "Ref Des/Assembly Top")
		(33 "B.Fab" user "Ref Des/Assembly Bottom")
	)
	(footprint ""
		(layer "F.Cu")
		(at 177.165 -80.137 90)
		(property "Reference" "R4D20"
			(at 0 0 90)
			(layer "F.SilkS")
			(hide yes)
			(effects
				(font
					(size 1.27 1.27)
				)
			)
		)
		(property "Value" ""
			(at 0 0 90)
			(layer "F.Fab")
			(effects
				(font
					(size 1.27 1.27)
				)
			)
		)
		(duplicate_pad_numbers_are_jumpers no)
		(fp_poly
			(pts
				(xy -0.2794 -0.1016) (xy 0.2794 -0.1016) (xy 0.2794 0.9906) (xy -0.2794 0.9906)
			)
			(stroke
				(width 0)
				(type default)
			)
			(fill no)
			(layer "F.CrtYd")
		)
		(fp_line
			(start 0.2794 -0.1016)
			(end -0.2794 -0.1016)
			(stroke
				(width 0.1)
				(type default)
			)
			(layer "F.Fab")
		)
		(fp_line
			(start -0.2794 -0.1016)
			(end -0.2794 0.9906)
			(stroke
				(width 0.1)
				(type default)
			)
			(layer "F.Fab")
		)
		(fp_line
			(start 0.2794 0.9906)
			(end 0.2794 -0.1016)
			(stroke
				(width 0.1)
				(type default)
			)
			(layer "F.Fab")
		)
		(fp_line
			(start -0.2794 0.9906)
			(end 0.2794 0.9906)
			(stroke
				(width 0.1)
				(type default)
			)
			(layer "F.Fab")
		)
		(pad "1" smd rect
			(at 0 0 90)
			(size 0.508 0.508)
			(layers "F.Cu" "F.Mask" "F.Paste")
			(net "CLK_100M_CPU0_BCLK1_R_DN")
		)
		(pad "2" smd rect
			(at 0 0.889 90)
			(size 0.508 0.508)
			(layers "F.Cu" "F.Mask" "F.Paste")
			(net "CLK_100M_CPU0_BCLK1_DN")
		)
		(zone
			(layer "F.Cu")
			(hatch none 0.5)
			(connect_pads
				(clearance 0)
			)
			(min_thickness 0.25)
			(keepout
				(tracks allowed)
				(vias not_allowed)
				(pads allowed)
				(copperpour not_allowed)
				(footprints allowed)
			)
			(placement
				(enabled no)
				(sheetname "")
			)
			(fill
				(thermal_gap 0.5)
				(thermal_bridge_width 0.5)
				(island_removal_mode 0)
			)
			(polygon
				(pts
					(xy 177.419 -79.883) (xy 177.419 -80.391) (xy 177.8 -80.391) (xy 177.8 -79.883)
				)
			)
		)
		(zone
			(layer "F.Cu")
			(hatch none 0.5)
			(connect_pads
				(clearance 0)
			)
			(min_thickness 0.25)
			(keepout
				(tracks not_allowed)
				(vias allowed)
				(pads allowed)
				(copperpour not_allowed)
				(footprints allowed)
			)
			(placement
				(enabled no)
				(sheetname "")
			)
			(fill
				(thermal_gap 0.5)
				(thermal_bridge_width 0.5)
				(island_removal_mode 0)
			)
			(polygon
				(pts
					(xy 177.8 -79.883) (xy 177.8 -80.391) (xy 177.419 -80.391) (xy 177.419 -79.883)
				)
			)
		)
	)
	(footprint ""
		(layer "F.Cu")
		(at 481.6983 -137.033 90)
		(property "Reference" "R9A20"
			(at 0 0 90)
			(layer "F.SilkS")
			(hide yes)
			(effects
				(font
					(size 1.27 1.27)
				)
			)
		)
		(property "Value" ""
			(at 0 0 90)
			(layer "F.Fab")
			(effects
				(font
					(size 1.27 1.27)
				)
			)
		)
		(duplicate_pad_numbers_are_jumpers no)
		(fp_poly
			(pts
				(xy -0.2794 -0.1016) (xy 0.2794 -0.1016) (xy 0.2794 0.9906) (xy -0.2794 0.9906)
			)
			(stroke
				(width 0)
				(type default)
			)
			(fill no)
			(layer "F.CrtYd")
		)
		(fp_line
			(start 0.2794 -0.1016)
			(end -0.2794 -0.1016)
			(stroke
				(width 0.1)
				(type default)
			)
			(layer "F.Fab")
		)
		(fp_line
			(start -0.2794 -0.1016)
			(end -0.2794 0.9906)
			(stroke
				(width 0.1)
				(type default)
			)
			(layer "F.Fab")
		)
		(fp_line
			(start 0.2794 0.9906)
			(end 0.2794 -0.1016)
			(stroke
				(width 0.1)
				(type default)
			)
			(layer "F.Fab")
		)
		(fp_line
			(start -0.2794 0.9906)
			(end 0.2794 0.9906)
			(stroke
				(width 0.1)
				(type default)
			)
			(layer "F.Fab")
		)
		(pad "1" smd rect
			(at 0 0 90)
			(size 0.508 0.508)
			(layers "F.Cu" "F.Mask" "F.Paste")
			(net "FM_PWR_LED_A")
		)
		(pad "2" smd rect
			(at 0 0.889 90)
			(size 0.508 0.508)
			(layers "F.Cu" "F.Mask" "F.Paste")
			(net "P3V3_STBY")
		)
		(zone
			(layer "F.Cu")
			(hatch none 0.5)
			(connect_pads
				(clearance 0)
			)
			(min_thickness 0.25)
			(keepout
				(tracks allowed)
				(vias not_allowed)
				(pads allowed)
				(copperpour not_allowed)
				(footprints allowed)
			)
			(placement
				(enabled no)
				(sheetname "")
			)
			(fill
				(thermal_gap 0.5)
				(thermal_bridge_width 0.5)
				(island_removal_mode 0)
			)
			(polygon
				(pts
					(xy 481.9523 -136.779) (xy 481.9523 -137.287) (xy 482.3333 -137.287) (xy 482.3333 -136.779)
				)
			)
		)
		(zone
			(layer "F.Cu")
			(hatch none 0.5)
			(connect_pads
				(clearance 0)
			)
			(min_thickness 0.25)
			(keepout
				(tracks not_allowed)
				(vias allowed)
				(pads allowed)
				(copperpour not_allowed)
				(footprints allowed)
			)
			(placement
				(enabled no)
				(sheetname "")
			)
			(fill
				(thermal_gap 0.5)
				(thermal_bridge_width 0.5)
				(island_removal_mode 0)
			)
			(polygon
				(pts
					(xy 482.3333 -136.779) (xy 482.3333 -137.287) (xy 481.9523 -137.287) (xy 481.9523 -136.779)
				)
			)
		)
	)
	(footprint ""
		(layer "F.Cu")
		(at 16.002 -87.63)
		(property "Reference" "R1D1"
			(at 0 0 0)
			(layer "F.SilkS")
			(hide yes)
			(effects
				(font
					(size 1.27 1.27)
				)
			)
		)
		(property "Value" ""
			(at 0 0 0)
			(layer "F.Fab")
			(effects
				(font
					(size 1.27 1.27)
				)
			)
		)
		(duplicate_pad_numbers_are_jumpers no)
		(fp_rect
			(start -0.2794 0.9906)
			(end 0.2794 -0.1016)
			(stroke
				(width 0)
				(type default)
			)
			(fill no)
			(layer "F.CrtYd")
		)
		(fp_line
			(start -0.2794 -0.1016)
			(end -0.2794 0.9906)
			(stroke
				(width 0.1)
				(type default)
			)
			(layer "F.Fab")
		)
		(fp_line
			(start -0.2794 0.9906)
			(end 0.2794 0.9906)
			(stroke
				(width 0.1)
				(type default)
			)
			(layer "F.Fab")
		)
		(fp_line
			(start 0.2794 -0.1016)
			(end -0.2794 -0.1016)
			(stroke
				(width 0.1)
				(type default)
			)
			(layer "F.Fab")
		)
		(fp_line
			(start 0.2794 0.9906)
			(end 0.2794 -0.1016)
			(stroke
				(width 0.1)
				(type default)
			)
			(layer "F.Fab")
		)
		(pad "1" smd rect
			(at 0 0)
			(size 0.508 0.508)
			(layers "F.Cu" "F.Mask" "F.Paste")
			(net "PWRGD_PVSA_CPU1_R")
		)
		(pad "2" smd rect
			(at 0 0.889)
			(size 0.508 0.508)
			(layers "F.Cu" "F.Mask" "F.Paste")
			(net "PWRGD_PVSA_CPU1")
		)
		(zone
			(layer "F.Cu")
			(hatch none 0.5)
			(connect_pads
				(clearance 0)
			)
			(min_thickness 0.25)
			(keepout
				(tracks not_allowed)
				(vias allowed)
				(pads allowed)
				(copperpour not_allowed)
				(footprints allowed)
			)
			(placement
				(enabled no)
				(sheetname "")
			)
			(fill
				(thermal_gap 0.5)
				(thermal_bridge_width 0.5)
				(island_removal_mode 0)
			)
			(polygon
				(pts
					(xy 15.748 -86.995) (xy 16.256 -86.995) (xy 16.256 -87.376) (xy 15.748 -87.376)
				)
			)
		)
		(zone
			(layer "F.Cu")
			(hatch none 0.5)
			(connect_pads
				(clearance 0)
			)
			(min_thickness 0.25)
			(keepout
				(tracks allowed)
				(vias not_allowed)
				(pads allowed)
				(copperpour not_allowed)
				(footprints allowed)
			)
			(placement
				(enabled no)
				(sheetname "")
			)
			(fill
				(thermal_gap 0.5)
				(thermal_bridge_width 0.5)
				(island_removal_mode 0)
			)
			(polygon
				(pts
					(xy 15.748 -86.995) (xy 16.256 -86.995) (xy 16.256 -87.376) (xy 15.748 -87.376)
				)
			)
		)
	)
)
